(kicad_pcb
	(version 20260206)
	(generator "pcbnew")
	(generator_version "10.0")
	(general
		(thickness 1.6)
		(legacy_teardrops no)
	)
	(paper "A4")
	(title_block
		(title "peb — Lightning_PEB_BRD.brd")
		(comment 1 "Lightning (Wiwynn / Facebook NVMe JBOF) / footprints 1536-1542 of 2563")
	)
	(layers
		(0 "F.Cu" signal "TOP")
		(4 "In1.Cu" signal "L2GND")
		(6 "In2.Cu" signal "L3")
		(8 "In3.Cu" signal "L4VCC")
		(10 "In4.Cu" signal "L5VCC")
		(12 "In5.Cu" signal "L6")
		(14 "In6.Cu" signal "L7GND")
		(2 "B.Cu" signal "BOTTOM")
		(9 "F.Adhes" user "F.Adhesive")
		(11 "B.Adhes" user "B.Adhesive")
		(13 "F.Paste" user "Package Geometry/Pastemask Top")
		(15 "B.Paste" user "Package Geometry/Pastemask Bottom")
		(5 "F.SilkS" user "Ref Des/Silkscreen Top")
		(7 "B.SilkS" user "Ref Des/Silkscreen Bottom")
		(1 "F.Mask" user "Board Geometry/Soldermask Top")
		(3 "B.Mask" user "Board Geometry/Soldermask Bottom")
		(17 "Dwgs.User" user "User.Drawings")
		(19 "Cmts.User" user "User.Comments")
		(21 "Eco1.User" user "User.Eco1")
		(23 "Eco2.User" user "User.Eco2")
		(25 "Edge.Cuts" user "Board Geometry/Outline")
		(27 "Margin" user)
		(31 "F.CrtYd" user "Package Geometry/Place Bound Top")
		(29 "B.CrtYd" user "Package Geometry/Place Bound Bottom")
		(35 "F.Fab" user "Ref Des/Assembly Top")
		(33 "B.Fab" user "Ref Des/Assembly Bottom")
	)
	(footprint ""
		(layer "F.Cu")
		(at 23.876 -135.763 90)
		(property "Reference" "R358"
			(at 0 0 90)
			(layer "F.SilkS")
			(hide yes)
			(effects
				(font
					(size 1.27 1.27)
				)
			)
		)
		(property "Value" "3K3R2F-2-GP"
			(at 0.064008 -3.993896 90)
			(unlocked yes)
			(layer "F.Fab")
			(hide yes)
			(effects
				(font
					(size 1.016 1.016)
					(thickness 0.1524)
				)
			)
		)
		(property "Device Type" "R402H16"
			(at 0.064008 -5.517896 90)
			(unlocked yes)
			(layer "F.Fab")
			(hide yes)
			(effects
				(font
					(size 1.016 1.016)
					(thickness 0.1524)
				)
			)
		)
		(duplicate_pad_numbers_are_jumpers no)
		(fp_line
			(start 0.508 -0.9398)
			(end -0.508 -0.9398)
			(stroke
				(width 0.1524)
				(type default)
			)
			(layer "F.SilkS")
		)
		(fp_line
			(start -0.508 -0.9398)
			(end -0.508 0.9398)
			(stroke
				(width 0.1524)
				(type default)
			)
			(layer "F.SilkS")
		)
		(fp_rect
			(start -0.508 0.9398)
			(end 0.508 -0.9398)
			(stroke
				(width 0)
				(type default)
			)
			(fill no)
			(layer "F.CrtYd")
		)
		(fp_rect
			(start -0.508 0.9398)
			(end 0.508 -0.9398)
			(stroke
				(width 0)
				(type default)
			)
			(fill no)
			(layer "F.Fab")
		)
		(pad "1" smd custom
			(at 0 -0.4445 90)
			(size 0.1397 0.1397)
			(layers "F.Cu" "F.Mask" "F.Paste")
			(net "P3V3_STBY")
			(options
				(clearance outline)
				(anchor circle)
			)
			(primitives
				(gr_poly
					(pts
						(arc
							(start -0.1778 -0.2794)
							(mid -0.249642 -0.249642)
							(end -0.2794 -0.1778)
						)
						(arc
							(start -0.2794 0.1778)
							(mid -0.249642 0.249642)
							(end -0.1778 0.2794)
						)
						(arc
							(start 0.1778 0.2794)
							(mid 0.249642 0.249642)
							(end 0.2794 0.1778)
						)
						(arc
							(start 0.2794 -0.1778)
							(mid 0.249642 -0.249642)
							(end 0.1778 -0.2794)
						)
					)
					(width 0)
					(fill yes)
				)
			)
		)
		(pad "2" smd custom
			(at 0 0.4445 90)
			(size 0.1397 0.1397)
			(layers "F.Cu" "F.Mask" "F.Paste")
			(net "ROMD4")
			(options
				(clearance outline)
				(anchor circle)
			)
			(primitives
				(gr_poly
					(pts
						(arc
							(start -0.1778 -0.2794)
							(mid -0.249642 -0.249642)
							(end -0.2794 -0.1778)
						)
						(arc
							(start -0.2794 0.1778)
							(mid -0.249642 0.249642)
							(end -0.1778 0.2794)
						)
						(arc
							(start 0.1778 0.2794)
							(mid 0.249642 0.249642)
							(end 0.2794 0.1778)
						)
						(arc
							(start 0.2794 -0.1778)
							(mid 0.249642 -0.249642)
							(end 0.1778 -0.2794)
						)
					)
					(width 0)
					(fill yes)
				)
			)
		)
	)
	(footprint ""
		(layer "F.Cu")
		(at 166.116 -91.9734 90)
		(property "Reference" "R3106"
			(at 0 0 90)
			(layer "F.SilkS")
			(hide yes)
			(effects
				(font
					(size 1.27 1.27)
				)
			)
		)
		(property "Value" "27R2F-GP"
			(at 0.064008 -3.993896 90)
			(unlocked yes)
			(layer "F.Fab")
			(hide yes)
			(effects
				(font
					(size 1.016 1.016)
					(thickness 0.1524)
				)
			)
		)
		(property "Device Type" "R402H16"
			(at 0.064008 -5.517896 90)
			(unlocked yes)
			(layer "F.Fab")
			(hide yes)
			(effects
				(font
					(size 1.016 1.016)
					(thickness 0.1524)
				)
			)
		)
		(duplicate_pad_numbers_are_jumpers no)
		(fp_line
			(start 0.508 -0.9398)
			(end -0.508 -0.9398)
			(stroke
				(width 0.1524)
				(type default)
			)
			(layer "F.SilkS")
		)
		(fp_line
			(start -0.508 -0.9398)
			(end -0.508 0.9398)
			(stroke
				(width 0.1524)
				(type default)
			)
			(layer "F.SilkS")
		)
		(fp_rect
			(start -0.508 0.9398)
			(end 0.508 -0.9398)
			(stroke
				(width 0)
				(type default)
			)
			(fill no)
			(layer "F.CrtYd")
		)
		(fp_rect
			(start -0.508 0.9398)
			(end 0.508 -0.9398)
			(stroke
				(width 0)
				(type default)
			)
			(fill no)
			(layer "F.Fab")
		)
		(pad "1" smd custom
			(at 0 -0.4445 90)
			(size 0.1397 0.1397)
			(layers "F.Cu" "F.Mask" "F.Paste")
			(net "CLKGEN_P2_R")
			(options
				(clearance outline)
				(anchor circle)
			)
			(primitives
				(gr_poly
					(pts
						(arc
							(start -0.1778 -0.2794)
							(mid -0.249642 -0.249642)
							(end -0.2794 -0.1778)
						)
						(arc
							(start -0.2794 0.1778)
							(mid -0.249642 0.249642)
							(end -0.1778 0.2794)
						)
						(arc
							(start 0.1778 0.2794)
							(mid 0.249642 0.249642)
							(end 0.2794 0.1778)
						)
						(arc
							(start 0.2794 -0.1778)
							(mid 0.249642 -0.249642)
							(end 0.1778 -0.2794)
						)
					)
					(width 0)
					(fill yes)
				)
			)
		)
		(pad "2" smd custom
			(at 0 0.4445 90)
			(size 0.1397 0.1397)
			(layers "F.Cu" "F.Mask" "F.Paste")
			(net "CLKGEN_P2")
			(options
				(clearance outline)
				(anchor circle)
			)
			(primitives
				(gr_poly
					(pts
						(arc
							(start -0.1778 -0.2794)
							(mid -0.249642 -0.249642)
							(end -0.2794 -0.1778)
						)
						(arc
							(start -0.2794 0.1778)
							(mid -0.249642 0.249642)
							(end -0.1778 0.2794)
						)
						(arc
							(start 0.1778 0.2794)
							(mid 0.249642 0.249642)
							(end 0.2794 0.1778)
						)
						(arc
							(start 0.2794 -0.1778)
							(mid 0.249642 -0.249642)
							(end 0.1778 -0.2794)
						)
					)
					(width 0)
					(fill yes)
				)
			)
		)
	)
	(footprint ""
		(layer "F.Cu")
		(at 338.792058 -212.420454 180)
		(property "Reference" "C56"
			(at 0 0 180)
			(layer "F.SilkS")
			(hide yes)
			(effects
				(font
					(size 1.27 1.27)
				)
			)
		)
		(property "Value" "SCD22U10V2KX-1GP"
			(at 1.1811 -2.7051 180)
			(unlocked yes)
			(layer "F.Fab")
			(hide yes)
			(effects
				(font
					(size 1.016 1.016)
					(thickness 0.1524)
				)
			)
		)
		(property "Device Type" "C402H22"
			(at 1.1811 -4.2291 180)
			(unlocked yes)
			(layer "F.Fab")
			(hide yes)
			(effects
				(font
					(size 1.016 1.016)
					(thickness 0.1524)
				)
			)
		)
		(duplicate_pad_numbers_are_jumpers no)
		(fp_rect
			(start -0.4318 0.9525)
			(end 0.4318 -0.9525)
			(stroke
				(width 0)
				(type default)
			)
			(fill no)
			(layer "F.CrtYd")
		)
		(fp_rect
			(start -0.4318 0.9525)
			(end 0.4318 -0.9525)
			(stroke
				(width 0)
				(type default)
			)
			(fill no)
			(layer "F.Fab")
		)
		(pad "1" smd custom
			(at 0 -0.4445 180)
			(size 0.1524 0.1524)
			(layers "F.Cu" "F.Mask" "F.Paste")
			(net "PCIE_TX_CAP_P17")
			(options
				(clearance outline)
				(anchor circle)
			)
			(primitives
				(gr_poly
					(pts
						(arc
							(start 0.3048 -0.2032)
							(mid 0.275042 -0.275042)
							(end 0.2032 -0.3048)
						)
						(arc
							(start -0.2032 -0.3048)
							(mid -0.275042 -0.275042)
							(end -0.3048 -0.2032)
						)
						(arc
							(start -0.3048 0.2032)
							(mid -0.275042 0.275042)
							(end -0.2032 0.3048)
						)
						(arc
							(start 0.2032 0.3048)
							(mid 0.275042 0.275042)
							(end 0.3048 0.2032)
						)
					)
					(width 0)
					(fill yes)
				)
			)
		)
		(pad "2" smd custom
			(at 0 0.4445 180)
			(size 0.1524 0.1524)
			(layers "F.Cu" "F.Mask" "F.Paste")
			(net "PCIE_TX_P17")
			(options
				(clearance outline)
				(anchor circle)
			)
			(primitives
				(gr_poly
					(pts
						(arc
							(start 0.3048 -0.2032)
							(mid 0.275042 -0.275042)
							(end 0.2032 -0.3048)
						)
						(arc
							(start -0.2032 -0.3048)
							(mid -0.275042 -0.275042)
							(end -0.3048 -0.2032)
						)
						(arc
							(start -0.3048 0.2032)
							(mid -0.275042 0.275042)
							(end -0.2032 0.3048)
						)
						(arc
							(start 0.2032 0.3048)
							(mid 0.275042 0.275042)
							(end 0.3048 0.2032)
						)
					)
					(width 0)
					(fill yes)
				)
			)
		)
	)
	(footprint ""
		(layer "F.Cu")
		(at 277.191978 -212.420454 180)
		(property "Reference" "C99"
			(at 0 0 180)
			(layer "F.SilkS")
			(hide yes)
			(effects
				(font
					(size 1.27 1.27)
				)
			)
		)
		(property "Value" "SCD22U10V2KX-1GP"
			(at 1.1811 -2.7051 180)
			(unlocked yes)
			(layer "F.Fab")
			(hide yes)
			(effects
				(font
					(size 1.016 1.016)
					(thickness 0.1524)
				)
			)
		)
		(property "Device Type" "C402H22"
			(at 1.1811 -4.2291 180)
			(unlocked yes)
			(layer "F.Fab")
			(hide yes)
			(effects
				(font
					(size 1.016 1.016)
					(thickness 0.1524)
				)
			)
		)
		(duplicate_pad_numbers_are_jumpers no)
		(fp_rect
			(start -0.4318 0.9525)
			(end 0.4318 -0.9525)
			(stroke
				(width 0)
				(type default)
			)
			(fill no)
			(layer "F.CrtYd")
		)
		(fp_rect
			(start -0.4318 0.9525)
			(end 0.4318 -0.9525)
			(stroke
				(width 0)
				(type default)
			)
			(fill no)
			(layer "F.Fab")
		)
		(pad "1" smd custom
			(at 0 -0.4445 180)
			(size 0.1524 0.1524)
			(layers "F.Cu" "F.Mask" "F.Paste")
			(net "PCIE_TX_CAP_P33")
			(options
				(clearance outline)
				(anchor circle)
			)
			(primitives
				(gr_poly
					(pts
						(arc
							(start 0.3048 -0.2032)
							(mid 0.275042 -0.275042)
							(end 0.2032 -0.3048)
						)
						(arc
							(start -0.2032 -0.3048)
							(mid -0.275042 -0.275042)
							(end -0.3048 -0.2032)
						)
						(arc
							(start -0.3048 0.2032)
							(mid -0.275042 0.275042)
							(end -0.2032 0.3048)
						)
						(arc
							(start 0.2032 0.3048)
							(mid 0.275042 0.275042)
							(end 0.3048 0.2032)
						)
					)
					(width 0)
					(fill yes)
				)
			)
		)
		(pad "2" smd custom
			(at 0 0.4445 180)
			(size 0.1524 0.1524)
			(layers "F.Cu" "F.Mask" "F.Paste")
			(net "PCIE_TX_P33")
			(options
				(clearance outline)
				(anchor circle)
			)
			(primitives
				(gr_poly
					(pts
						(arc
							(start 0.3048 -0.2032)
							(mid 0.275042 -0.275042)
							(end 0.2032 -0.3048)
						)
						(arc
							(start -0.2032 -0.3048)
							(mid -0.275042 -0.275042)
							(end -0.3048 -0.2032)
						)
						(arc
							(start -0.3048 0.2032)
							(mid -0.275042 0.275042)
							(end -0.2032 0.3048)
						)
						(arc
							(start 0.2032 0.3048)
							(mid 0.275042 0.275042)
							(end 0.3048 0.2032)
						)
					)
					(width 0)
					(fill yes)
				)
			)
		)
	)
	(footprint ""
		(layer "F.Cu")
		(at 27.051 -70.8406 180)
		(property "Reference" "R404"
			(at 0 0 180)
			(layer "F.SilkS")
			(hide yes)
			(effects
				(font
					(size 1.27 1.27)
				)
			)
		)
		(property "Value" "3K3R2F-2-GP"
			(at 0.064008 -3.993896 180)
			(unlocked yes)
			(layer "F.Fab")
			(hide yes)
			(effects
				(font
					(size 1.016 1.016)
					(thickness 0.1524)
				)
			)
		)
		(property "Device Type" "R402H16"
			(at 0.064008 -5.517896 180)
			(unlocked yes)
			(layer "F.Fab")
			(hide yes)
			(effects
				(font
					(size 1.016 1.016)
					(thickness 0.1524)
				)
			)
		)
		(duplicate_pad_numbers_are_jumpers no)
		(fp_line
			(start 0.508 -0.9398)
			(end -0.508 -0.9398)
			(stroke
				(width 0.1524)
				(type default)
			)
			(layer "F.SilkS")
		)
		(fp_line
			(start -0.508 -0.9398)
			(end -0.508 0.9398)
			(stroke
				(width 0.1524)
				(type default)
			)
			(layer "F.SilkS")
		)
		(fp_rect
			(start -0.508 0.9398)
			(end 0.508 -0.9398)
			(stroke
				(width 0)
				(type default)
			)
			(fill no)
			(layer "F.CrtYd")
		)
		(fp_rect
			(start -0.508 0.9398)
			(end 0.508 -0.9398)
			(stroke
				(width 0)
				(type default)
			)
			(fill no)
			(layer "F.Fab")
		)
		(pad "1" smd custom
			(at 0 -0.4445 180)
			(size 0.1397 0.1397)
			(layers "F.Cu" "F.Mask" "F.Paste")
			(net "P3V3_STBY")
			(options
				(clearance outline)
				(anchor circle)
			)
			(primitives
				(gr_poly
					(pts
						(arc
							(start -0.1778 -0.2794)
							(mid -0.249642 -0.249642)
							(end -0.2794 -0.1778)
						)
						(arc
							(start -0.2794 0.1778)
							(mid -0.249642 0.249642)
							(end -0.1778 0.2794)
						)
						(arc
							(start 0.1778 0.2794)
							(mid 0.249642 0.249642)
							(end 0.2794 0.1778)
						)
						(arc
							(start 0.2794 -0.1778)
							(mid 0.249642 -0.249642)
							(end 0.1778 -0.2794)
						)
					)
					(width 0)
					(fill yes)
				)
			)
		)
		(pad "2" smd custom
			(at 0 0.4445 180)
			(size 0.1397 0.1397)
			(layers "F.Cu" "F.Mask" "F.Paste")
			(net "NIC_JTDO")
			(options
				(clearance outline)
				(anchor circle)
			)
			(primitives
				(gr_poly
					(pts
						(arc
							(start -0.1778 -0.2794)
							(mid -0.249642 -0.249642)
							(end -0.2794 -0.1778)
						)
						(arc
							(start -0.2794 0.1778)
							(mid -0.249642 0.249642)
							(end -0.1778 0.2794)
						)
						(arc
							(start 0.1778 0.2794)
							(mid 0.249642 0.249642)
							(end 0.2794 0.1778)
						)
						(arc
							(start 0.2794 -0.1778)
							(mid 0.249642 -0.249642)
							(end 0.1778 -0.2794)
						)
					)
					(width 0)
					(fill yes)
				)
			)
		)
	)
	(footprint ""
		(layer "F.Cu")
		(at 292.227 -59.563 -90)
		(property "Reference" "R643"
			(at 0 0 270)
			(layer "F.SilkS")
			(hide yes)
			(effects
				(font
					(size 1.27 1.27)
				)
			)
		)
		(property "Value" "0R2J-2-GP"
			(at 0.064008 -3.993896 270)
			(unlocked yes)
			(layer "F.Fab")
			(hide yes)
			(effects
				(font
					(size 1.016 1.016)
					(thickness 0.1524)
				)
			)
		)
		(property "Device Type" "R402H16"
			(at 0.064008 -5.517896 270)
			(unlocked yes)
			(layer "F.Fab")
			(hide yes)
			(effects
				(font
					(size 1.016 1.016)
					(thickness 0.1524)
				)
			)
		)
		(duplicate_pad_numbers_are_jumpers no)
		(fp_line
			(start -0.508 -0.9398)
			(end -0.508 0.9398)
			(stroke
				(width 0.1524)
				(type default)
			)
			(layer "F.SilkS")
		)
		(fp_line
			(start 0.508 -0.9398)
			(end -0.508 -0.9398)
			(stroke
				(width 0.1524)
				(type default)
			)
			(layer "F.SilkS")
		)
		(fp_rect
			(start -0.508 0.9398)
			(end 0.508 -0.9398)
			(stroke
				(width 0)
				(type default)
			)
			(fill no)
			(layer "F.CrtYd")
		)
		(fp_rect
			(start -0.508 0.9398)
			(end 0.508 -0.9398)
			(stroke
				(width 0)
				(type default)
			)
			(fill no)
			(layer "F.Fab")
		)
		(pad "1" smd custom
			(at 0 -0.4445 270)
			(size 0.1397 0.1397)
			(layers "F.Cu" "F.Mask" "F.Paste")
			(net "VS6_LED_R")
			(options
				(clearance outline)
				(anchor circle)
			)
			(primitives
				(gr_poly
					(pts
						(arc
							(start -0.1778 -0.2794)
							(mid -0.249642 -0.249642)
							(end -0.2794 -0.1778)
						)
						(arc
							(start -0.2794 0.1778)
							(mid -0.249642 0.249642)
							(end -0.1778 0.2794)
						)
						(arc
							(start 0.1778 0.2794)
							(mid 0.249642 0.249642)
							(end 0.2794 0.1778)
						)
						(arc
							(start 0.2794 -0.1778)
							(mid 0.249642 -0.249642)
							(end 0.1778 -0.2794)
						)
					)
					(width 0)
					(fill yes)
				)
			)
		)
		(pad "2" smd custom
			(at 0 0.4445 270)
			(size 0.1397 0.1397)
			(layers "F.Cu" "F.Mask" "F.Paste")
			(net "VS6_LED")
			(options
				(clearance outline)
				(anchor circle)
			)
			(primitives
				(gr_poly
					(pts
						(arc
							(start -0.1778 -0.2794)
							(mid -0.249642 -0.249642)
							(end -0.2794 -0.1778)
						)
						(arc
							(start -0.2794 0.1778)
							(mid -0.249642 0.249642)
							(end -0.1778 0.2794)
						)
						(arc
							(start 0.1778 0.2794)
							(mid 0.249642 0.249642)
							(end 0.2794 0.1778)
						)
						(arc
							(start 0.2794 -0.1778)
							(mid 0.249642 -0.249642)
							(end 0.1778 -0.2794)
						)
					)
					(width 0)
					(fill yes)
				)
			)
		)
	)
	(footprint ""
		(layer "F.Cu")
		(at 227.179124 -203.047092 180)
		(property "Reference" "R7947"
			(at 0 0 180)
			(layer "F.SilkS")
			(hide yes)
			(effects
				(font
					(size 1.27 1.27)
				)
			)
		)
		(property "Value" "0R2J-2-GP"
			(at 0.064008 -3.993896 180)
			(unlocked yes)
			(layer "F.Fab")
			(hide yes)
			(effects
				(font
					(size 1.016 1.016)
					(thickness 0.1524)
				)
			)
		)
		(property "Device Type" "R402H16"
			(at 0.064008 -5.517896 180)
			(unlocked yes)
			(layer "F.Fab")
			(hide yes)
			(effects
				(font
					(size 1.016 1.016)
					(thickness 0.1524)
				)
			)
		)
		(duplicate_pad_numbers_are_jumpers no)
		(fp_line
			(start 0.508 -0.9398)
			(end -0.508 -0.9398)
			(stroke
				(width 0.1524)
				(type default)
			)
			(layer "F.SilkS")
		)
		(fp_line
			(start -0.508 -0.9398)
			(end -0.508 0.9398)
			(stroke
				(width 0.1524)
				(type default)
			)
			(layer "F.SilkS")
		)
		(fp_rect
			(start -0.508 0.9398)
			(end 0.508 -0.9398)
			(stroke
				(width 0)
				(type default)
			)
			(fill no)
			(layer "F.CrtYd")
		)
		(fp_rect
			(start -0.508 0.9398)
			(end 0.508 -0.9398)
			(stroke
				(width 0)
				(type default)
			)
			(fill no)
			(layer "F.Fab")
		)
		(pad "1" smd custom
			(at 0 -0.4445 180)
			(size 0.1397 0.1397)
			(layers "F.Cu" "F.Mask" "F.Paste")
			(net "SSD_ATNLED#12")
			(options
				(clearance outline)
				(anchor circle)
			)
			(primitives
				(gr_poly
					(pts
						(arc
							(start -0.1778 -0.2794)
							(mid -0.249642 -0.249642)
							(end -0.2794 -0.1778)
						)
						(arc
							(start -0.2794 0.1778)
							(mid -0.249642 0.249642)
							(end -0.1778 0.2794)
						)
						(arc
							(start 0.1778 0.2794)
							(mid 0.249642 0.249642)
							(end 0.2794 0.1778)
						)
						(arc
							(start 0.2794 -0.1778)
							(mid 0.249642 -0.249642)
							(end 0.1778 -0.2794)
						)
					)
					(width 0)
					(fill yes)
				)
			)
		)
		(pad "2" smd custom
			(at 0 0.4445 180)
			(size 0.1397 0.1397)
			(layers "F.Cu" "F.Mask" "F.Paste")
			(net "SSD_ATNLED#12_R")
			(options
				(clearance outline)
				(anchor circle)
			)
			(primitives
				(gr_poly
					(pts
						(arc
							(start -0.1778 -0.2794)
							(mid -0.249642 -0.249642)
							(end -0.2794 -0.1778)
						)
						(arc
							(start -0.2794 0.1778)
							(mid -0.249642 0.249642)
							(end -0.1778 0.2794)
						)
						(arc
							(start 0.1778 0.2794)
							(mid 0.249642 0.249642)
							(end 0.2794 0.1778)
						)
						(arc
							(start 0.2794 -0.1778)
							(mid 0.249642 -0.249642)
							(end 0.1778 -0.2794)
						)
					)
					(width 0)
					(fill yes)
				)
			)
		)
	)
)
